(kicad_pcb
	(version 20241229)
	(generator "pcbnew")
	(generator_version "9.0")
	(general
		(thickness 1.552)
		(legacy_teardrops no)
	)
	(paper "A4")
	(title_block
		(date "2023-07-25")
		(rev "1.1.4")
		(comment 9 "footprints 71-72 of 379")
	)
	(layers
		(0 "F.Cu" signal)
		(4 "In1.Cu" signal)
		(6 "In2.Cu" signal)
		(8 "In3.Cu" signal)
		(10 "In4.Cu" signal)
		(12 "In5.Cu" signal)
		(14 "In6.Cu" signal)
		(2 "B.Cu" signal)
		(9 "F.Adhes" user "F.Adhesive")
		(11 "B.Adhes" user "B.Adhesive")
		(13 "F.Paste" user)
		(15 "B.Paste" user)
		(5 "F.SilkS" user "F.Silkscreen")
		(7 "B.SilkS" user "B.Silkscreen")
		(1 "F.Mask" user)
		(3 "B.Mask" user)
		(17 "Dwgs.User" user "User.Drawings")
		(19 "Cmts.User" user "User.Comments")
		(21 "Eco1.User" user "User.Eco1")
		(23 "Eco2.User" user "User.Eco2")
		(25 "Edge.Cuts" user)
		(27 "Margin" user)
		(31 "F.CrtYd" user "F.Courtyard")
		(29 "B.CrtYd" user "B.Courtyard")
		(35 "F.Fab" user)
		(33 "B.Fab" user)
	)
	(footprint "antmicro-footprints:Conn_FFC_WE_68715014x22"
		(layer "F.Cu")
		(at 171.83 100.14 90)
		(property "Reference" "J4"
			(at -2.3 -3.4 90)
			(layer "F.SilkS")
			(effects
				(font
					(size 0.65 0.65)
					(thickness 0.15)
				)
				(justify left bottom)
			)
		)
		(property "Value" "Conn_FFC_WE_68715014522_ONE-SIDE"
			(at 0 4.5 90)
			(layer "F.Fab")
			(hide yes)
			(effects
				(font
					(size 0.7 0.7)
					(thickness 0.15)
				)
				(justify left bottom)
			)
		)
		(property "Datasheet" "https://www.we-online.com/components/products/datasheet/68715014522.pdf"
			(at 0 0 90)
			(layer "F.Fab")
			(hide yes)
			(effects
				(font
					(size 1.27 1.27)
					(thickness 0.15)
				)
			)
		)
		(property "Description" "FFC connector"
			(at 0 0 90)
			(layer "F.Fab")
			(hide yes)
			(effects
				(font
					(size 1.27 1.27)
					(thickness 0.15)
				)
			)
		)
		(property "Author" "Antmicro"
			(at 271.97 -71.69 0)
			(layer "F.Fab")
			(hide yes)
			(effects
				(font
					(size 1 1)
					(thickness 0.15)
				)
			)
		)
		(property "License" "Apache-2.0"
			(at 271.97 -71.69 0)
			(layer "F.Fab")
			(hide yes)
			(effects
				(font
					(size 1 1)
					(thickness 0.15)
				)
			)
		)
		(property "MPN" "68715014522"
			(at 271.97 -71.69 0)
			(layer "F.Fab")
			(hide yes)
			(effects
				(font
					(size 1 1)
					(thickness 0.15)
				)
			)
		)
		(property "Manufacturer" "Würth Elektronik"
			(at 271.97 -71.69 0)
			(layer "F.Fab")
			(hide yes)
			(effects
				(font
					(size 1 1)
					(thickness 0.15)
				)
			)
		)
		(sheetname "/Peripherals/")
		(sheetfile "peripherals.kicad_sch")
		(attr smd)
		(fp_line
			(start -12.5 -2.976)
			(end 12.499 -2.976)
			(stroke
				(width 0.15)
				(type solid)
			)
			(layer "F.SilkS")
		)
		(fp_line
			(start 15.85 -2.15)
			(end 12.499 -2.15)
			(stroke
				(width 0.15)
				(type solid)
			)
			(layer "F.SilkS")
		)
		(fp_line
			(start 12.499 -2.15)
			(end 12.499 -2.976)
			(stroke
				(width 0.15)
				(type solid)
			)
			(layer "F.SilkS")
		)
		(fp_line
			(start -12.5 -2.15)
			(end -12.5 -2.976)
			(stroke
				(width 0.15)
				(type solid)
			)
			(layer "F.SilkS")
		)
		(fp_line
			(start -15.85 -2.15)
			(end -12.5 -2.15)
			(stroke
				(width 0.15)
				(type solid)
			)
			(layer "F.SilkS")
		)
		(fp_line
			(start 15.85 2.7)
			(end 15.85 -2.15)
			(stroke
				(width 0.15)
				(type solid)
			)
			(layer "F.SilkS")
		)
		(fp_line
			(start 15.85 2.7)
			(end -15.85 2.7)
			(stroke
				(width 0.15)
				(type solid)
			)
			(layer "F.SilkS")
		)
		(fp_line
			(start -15.85 2.7)
			(end -15.85 -2.15)
			(stroke
				(width 0.15)
				(type solid)
			)
			(layer "F.SilkS")
		)
		(fp_circle
			(center -12.9 -2.9)
			(end -12.85 -2.85)
			(stroke
				(width 0.15)
				(type solid)
			)
			(fill yes)
			(layer "F.SilkS")
		)
		(fp_rect
			(start -16.2 -3.25)
			(end 16.2 3.55)
			(stroke
				(width 0.05)
				(type solid)
			)
			(fill no)
			(layer "F.CrtYd")
		)
		(fp_text user "${REFERENCE}"
			(at -16.2 5.9 90)
			(layer "F.Fab")
			(effects
				(font
					(size 0.7 0.7)
					(thickness 0.15)
				)
				(justify left bottom)
			)
		)
		(fp_text user "Author: Antmicro"
			(at -16.2 6.9 90)
			(layer "F.Fab")
			(effects
				(font
					(size 0.7 0.7)
					(thickness 0.15)
				)
				(justify left bottom)
			)
		)
		(fp_text user "License: Apache-2.0"
			(at -16.2 7.9 90)
			(layer "F.Fab")
			(effects
				(font
					(size 0.7 0.7)
					(thickness 0.15)
				)
				(justify left bottom)
			)
		)
		(pad "1" smd roundrect
			(at -12.25 -2.15 90)
			(size 0.3 1.2)
			(layers "F.Cu" "F.Mask" "F.Paste")
			(roundrect_rratio 0.25)
			(net 68 "/Peripherals/MIPI0_D3_N")
			(pintype "passive")
		)
		(pad "2" smd roundrect
			(at -11.75 -2.15 90)
			(size 0.3 1.2)
			(layers "F.Cu" "F.Mask" "F.Paste")
			(roundrect_rratio 0.25)
			(net 69 "/Peripherals/MIPI0_D3_P")
			(pintype "passive")
		)
		(pad "3" smd roundrect
			(at -11.25 -2.15 90)
			(size 0.3 1.2)
			(layers "F.Cu" "F.Mask" "F.Paste")
			(roundrect_rratio 0.25)
			(net 70 "/Peripherals/MIPI0_D2_N")
			(pintype "passive")
		)
		(pad "4" smd roundrect
			(at -10.75 -2.15 90)
			(size 0.3 1.2)
			(layers "F.Cu" "F.Mask" "F.Paste")
			(roundrect_rratio 0.25)
			(net 71 "/Peripherals/MIPI0_D2_P")
			(pintype "passive")
		)
		(pad "5" smd roundrect
			(at -10.25 -2.15 90)
			(size 0.3 1.2)
			(layers "F.Cu" "F.Mask" "F.Paste")
			(roundrect_rratio 0.25)
			(net 72 "/Peripherals/MIPI0_D1_N")
			(pintype "passive")
		)
		(pad "6" smd roundrect
			(at -9.75 -2.15 90)
			(size 0.3 1.2)
			(layers "F.Cu" "F.Mask" "F.Paste")
			(roundrect_rratio 0.25)
			(net 73 "/Peripherals/MIPI0_D1_P")
			(pintype "passive")
		)
		(pad "7" smd roundrect
			(at -9.25 -2.15 90)
			(size 0.3 1.2)
			(layers "F.Cu" "F.Mask" "F.Paste")
			(roundrect_rratio 0.25)
			(net 74 "/Peripherals/MIPI0_D0_N")
			(pintype "passive")
		)
		(pad "8" smd roundrect
			(at -8.75 -2.15 90)
			(size 0.3 1.2)
			(layers "F.Cu" "F.Mask" "F.Paste")
			(roundrect_rratio 0.25)
			(net 75 "/Peripherals/MIPI0_D0_P")
			(pintype "passive")
		)
		(pad "9" smd roundrect
			(at -8.25 -2.15 90)
			(size 0.3 1.2)
			(layers "F.Cu" "F.Mask" "F.Paste")
			(roundrect_rratio 0.25)
			(net 1 "GND")
			(pintype "passive")
		)
		(pad "10" smd roundrect
			(at -7.75 -2.15 90)
			(size 0.3 1.2)
			(layers "F.Cu" "F.Mask" "F.Paste")
			(roundrect_rratio 0.25)
			(net 76 "/Peripherals/MIPI0_CLK_N")
			(pintype "passive")
		)
		(pad "11" smd roundrect
			(at -7.25 -2.15 90)
			(size 0.3 1.2)
			(layers "F.Cu" "F.Mask" "F.Paste")
			(roundrect_rratio 0.25)
			(net 77 "/Peripherals/MIPI0_CLK_P")
			(pintype "passive")
		)
		(pad "12" smd roundrect
			(at -6.75 -2.15 90)
			(size 0.3 1.2)
			(layers "F.Cu" "F.Mask" "F.Paste")
			(roundrect_rratio 0.25)
			(net 1 "GND")
			(pintype "passive")
		)
		(pad "13" smd roundrect
			(at -6.25 -2.15 90)
			(size 0.3 1.2)
			(layers "F.Cu" "F.Mask" "F.Paste")
			(roundrect_rratio 0.25)
			(net 51 "unconnected-(J4-Pad13)")
			(pintype "passive+no_connect")
		)
		(pad "14" smd roundrect
			(at -5.75 -2.15 90)
			(size 0.3 1.2)
			(layers "F.Cu" "F.Mask" "F.Paste")
			(roundrect_rratio 0.25)
			(net 52 "unconnected-(J4-Pad14)")
			(pintype "passive+no_connect")
		)
		(pad "15" smd roundrect
			(at -5.25 -2.15 90)
			(size 0.3 1.2)
			(layers "F.Cu" "F.Mask" "F.Paste")
			(roundrect_rratio 0.25)
			(net 1 "GND")
			(pintype "passive")
		)
		(pad "16" smd roundrect
			(at -4.75 -2.15 90)
			(size 0.3 1.2)
			(layers "F.Cu" "F.Mask" "F.Paste")
			(roundrect_rratio 0.25)
			(net 53 "unconnected-(J4-Pad16)")
			(pintype "passive+no_connect")
		)
		(pad "17" smd roundrect
			(at -4.25 -2.15 90)
			(size 0.3 1.2)
			(layers "F.Cu" "F.Mask" "F.Paste")
			(roundrect_rratio 0.25)
			(net 54 "unconnected-(J4-Pad17)")
			(pintype "passive+no_connect")
		)
		(pad "18" smd roundrect
			(at -3.75 -2.15 90)
			(size 0.3 1.2)
			(layers "F.Cu" "F.Mask" "F.Paste")
			(roundrect_rratio 0.25)
			(net 1 "GND")
			(pintype "passive")
		)
		(pad "19" smd roundrect
			(at -3.25 -2.15 90)
			(size 0.3 1.2)
			(layers "F.Cu" "F.Mask" "F.Paste")
			(roundrect_rratio 0.25)
			(net 78 "/Peripherals/MIPI2_D3_N")
			(pintype "passive")
		)
		(pad "20" smd roundrect
			(at -2.75 -2.15 90)
			(size 0.3 1.2)
			(layers "F.Cu" "F.Mask" "F.Paste")
			(roundrect_rratio 0.25)
			(net 79 "/Peripherals/MIPI2_D3_P")
			(pintype "passive")
		)
		(pad "21" smd roundrect
			(at -2.25 -2.15 90)
			(size 0.3 1.2)
			(layers "F.Cu" "F.Mask" "F.Paste")
			(roundrect_rratio 0.25)
			(net 80 "/Peripherals/MIPI2_D2_N")
			(pintype "passive")
		)
		(pad "22" smd roundrect
			(at -1.75 -2.15 90)
			(size 0.3 1.2)
			(layers "F.Cu" "F.Mask" "F.Paste")
			(roundrect_rratio 0.25)
			(net 81 "/Peripherals/MIPI2_D2_P")
			(pintype "passive")
		)
		(pad "23" smd roundrect
			(at -1.25 -2.15 90)
			(size 0.3 1.2)
			(layers "F.Cu" "F.Mask" "F.Paste")
			(roundrect_rratio 0.25)
			(net 82 "/Peripherals/MIPI2_D1_N")
			(pintype "passive")
		)
		(pad "24" smd roundrect
			(at -0.75 -2.15 90)
			(size 0.3 1.2)
			(layers "F.Cu" "F.Mask" "F.Paste")
			(roundrect_rratio 0.25)
			(net 83 "/Peripherals/MIPI2_D1_P")
			(pintype "passive")
		)
		(pad "25" smd roundrect
			(at -0.25 -2.15 90)
			(size 0.3 1.2)
			(layers "F.Cu" "F.Mask" "F.Paste")
			(roundrect_rratio 0.25)
			(net 84 "/Peripherals/MIPI2_D0_N")
			(pintype "passive")
		)
		(pad "26" smd roundrect
			(at 0.248 -2.15 90)
			(size 0.3 1.2)
			(layers "F.Cu" "F.Mask" "F.Paste")
			(roundrect_rratio 0.25)
			(net 85 "/Peripherals/MIPI2_D0_P")
			(pintype "passive")
		)
		(pad "27" smd roundrect
			(at 0.748 -2.15 90)
			(size 0.3 1.2)
			(layers "F.Cu" "F.Mask" "F.Paste")
			(roundrect_rratio 0.25)
			(net 1 "GND")
			(pintype "passive")
		)
		(pad "28" smd roundrect
			(at 1.249 -2.15 90)
			(size 0.3 1.2)
			(layers "F.Cu" "F.Mask" "F.Paste")
			(roundrect_rratio 0.25)
			(net 86 "/Peripherals/MIPI2_CLK_N")
			(pintype "passive")
		)
		(pad "29" smd roundrect
			(at 1.749 -2.15 90)
			(size 0.3 1.2)
			(layers "F.Cu" "F.Mask" "F.Paste")
			(roundrect_rratio 0.25)
			(net 87 "/Peripherals/MIPI2_CLK_P")
			(pintype "passive")
		)
		(pad "30" smd roundrect
			(at 2.249 -2.15 90)
			(size 0.3 1.2)
			(layers "F.Cu" "F.Mask" "F.Paste")
			(roundrect_rratio 0.25)
			(net 1 "GND")
			(pintype "passive")
		)
		(pad "31" smd roundrect
			(at 2.749 -2.15 90)
			(size 0.3 1.2)
			(layers "F.Cu" "F.Mask" "F.Paste")
			(roundrect_rratio 0.25)
			(net 55 "unconnected-(J4-Pad31)")
			(pintype "passive+no_connect")
		)
		(pad "32" smd roundrect
			(at 3.249 -2.15 90)
			(size 0.3 1.2)
			(layers "F.Cu" "F.Mask" "F.Paste")
			(roundrect_rratio 0.25)
			(net 56 "Net-(J4-Pad32)")
			(pintype "passive")
		)
		(pad "33" smd roundrect
			(at 3.749 -2.15 90)
			(size 0.3 1.2)
			(layers "F.Cu" "F.Mask" "F.Paste")
			(roundrect_rratio 0.25)
			(net 336 "Net-(J4-Pad33)")
			(pintype "passive")
		)
		(pad "34" smd roundrect
			(at 4.248 -2.15 90)
			(size 0.3 1.2)
			(layers "F.Cu" "F.Mask" "F.Paste")
			(roundrect_rratio 0.25)
			(net 337 "Net-(J4-Pad34)")
			(pintype "passive")
		)
		(pad "35" smd roundrect
			(at 4.748 -2.15 90)
			(size 0.3 1.2)
			(layers "F.Cu" "F.Mask" "F.Paste")
			(roundrect_rratio 0.25)
			(net 338 "unconnected-(J4-Pad35)")
			(pintype "passive+no_connect")
		)
		(pad "36" smd roundrect
			(at 5.248 -2.15 90)
			(size 0.3 1.2)
			(layers "F.Cu" "F.Mask" "F.Paste")
			(roundrect_rratio 0.25)
			(net 339 "unconnected-(J4-Pad36)")
			(pintype "passive+no_connect")
		)
		(pad "37" smd roundrect
			(at 5.749 -2.15 90)
			(size 0.3 1.2)
			(layers "F.Cu" "F.Mask" "F.Paste")
			(roundrect_rratio 0.25)
			(net 340 "unconnected-(J4-Pad37)")
			(pintype "passive+no_connect")
		)
		(pad "38" smd roundrect
			(at 6.249 -2.15 90)
			(size 0.3 1.2)
			(layers "F.Cu" "F.Mask" "F.Paste")
			(roundrect_rratio 0.25)
			(net 341 "unconnected-(J4-Pad38)")
			(pintype "passive+no_connect")
		)
		(pad "39" smd roundrect
			(at 6.749 -2.15 90)
			(size 0.3 1.2)
			(layers "F.Cu" "F.Mask" "F.Paste")
			(roundrect_rratio 0.25)
			(net 342 "Net-(J4-Pad39)")
			(pintype "passive")
		)
		(pad "40" smd roundrect
			(at 7.249 -2.15 90)
			(size 0.3 1.2)
			(layers "F.Cu" "F.Mask" "F.Paste")
			(roundrect_rratio 0.25)
			(net 364 "Net-(J4-Pad40)")
			(pintype "passive")
		)
		(pad "41" smd roundrect
			(at 7.749 -2.15 90)
			(size 0.3 1.2)
			(layers "F.Cu" "F.Mask" "F.Paste")
			(roundrect_rratio 0.25)
			(net 365 "Net-(J4-Pad41)")
			(pintype "passive")
		)
		(pad "42" smd roundrect
			(at 8.249 -2.15 90)
			(size 0.3 1.2)
			(layers "F.Cu" "F.Mask" "F.Paste")
			(roundrect_rratio 0.25)
			(net 366 "Net-(J4-Pad42)")
			(pintype "passive")
		)
		(pad "43" smd roundrect
			(at 8.749 -2.15 90)
			(size 0.3 1.2)
			(layers "F.Cu" "F.Mask" "F.Paste")
			(roundrect_rratio 0.25)
			(net 367 "unconnected-(J4-Pad43)")
			(pintype "passive+no_connect")
		)
		(pad "44" smd roundrect
			(at 9.249 -2.15 90)
			(size 0.3 1.2)
			(layers "F.Cu" "F.Mask" "F.Paste")
			(roundrect_rratio 0.25)
			(net 368 "unconnected-(J4-Pad44)")
			(pintype "passive+no_connect")
		)
		(pad "45" smd roundrect
			(at 9.749 -2.15 90)
			(size 0.3 1.2)
			(layers "F.Cu" "F.Mask" "F.Paste")
			(roundrect_rratio 0.25)
			(net 369 "unconnected-(J4-Pad45)")
			(pintype "passive+no_connect")
		)
		(pad "46" smd roundrect
			(at 10.249 -2.15 90)
			(size 0.3 1.2)
			(layers "F.Cu" "F.Mask" "F.Paste")
			(roundrect_rratio 0.25)
			(net 370 "unconnected-(J4-Pad46)")
			(pintype "passive+no_connect")
		)
		(pad "47" smd roundrect
			(at 10.749 -2.15 90)
			(size 0.3 1.2)
			(layers "F.Cu" "F.Mask" "F.Paste")
			(roundrect_rratio 0.25)
			(net 17 "/Peripherals/FFC1_3V3")
			(pintype "passive")
		)
		(pad "48" smd roundrect
			(at 11.249 -2.15 90)
			(size 0.3 1.2)
			(layers "F.Cu" "F.Mask" "F.Paste")
			(roundrect_rratio 0.25)
			(net 17 "/Peripherals/FFC1_3V3")
			(pintype "passive")
		)
		(pad "49" smd roundrect
			(at 11.749 -2.15 90)
			(size 0.3 1.2)
			(layers "F.Cu" "F.Mask" "F.Paste")
			(roundrect_rratio 0.25)
			(net 16 "/Peripherals/FFC1_5V")
			(pintype "passive")
		)
		(pad "50" smd roundrect
			(at 12.249 -2.15 90)
			(size 0.3 1.2)
			(layers "F.Cu" "F.Mask" "F.Paste")
			(roundrect_rratio 0.25)
			(net 16 "/Peripherals/FFC1_5V")
			(pintype "passive")
		)
		(pad "MP1" smd roundrect
			(at -14.198 -0.3 90)
			(size 2.7 3)
			(layers "F.Cu" "F.Mask" "F.Paste")
			(roundrect_rratio 0.05)
			(net 1 "GND")
			(pinfunction "MP")
			(pintype "passive")
		)
		(pad "MP2" smd roundrect
			(at 14.198 -0.3 90)
			(size 2.7 3)
			(layers "F.Cu" "F.Mask" "F.Paste")
			(roundrect_rratio 0.05)
			(net 1 "GND")
			(pinfunction "MP")
			(pintype "passive")
		)
	)
	(footprint "antmicro-footprints:C_0402_1005Metric"
		(layer "F.Cu")
		(at 82.7 107.15 -90)
		(descr "Capacitor SMD 0402")
		(tags "capacitor SMD 0402")
		(property "Reference" "C76"
			(at -9.31 -3.53 90)
			(layer "F.SilkS")
			(effects
				(font
					(size 0.65 0.65)
					(thickness 0.15)
				)
				(justify right bottom)
			)
		)
		(property "Value" "C_10n_0402"
			(at 0 1.4 90)
			(layer "F.Fab")
			(hide yes)
			(effects
				(font
					(size 0.7 0.7)
					(thickness 0.15)
				)
				(justify right bottom)
			)
		)
		(property "Datasheet" "https://www.murata.com/products/productdetail?partno=GRM155R71H103KA88%23"
			(at 0 0 270)
			(layer "F.Fab")
			(hide yes)
			(effects
				(font
					(size 1.27 1.27)
					(thickness 0.15)
				)
			)
		)
		(property "Description" "SMD Multilayer Ceramic Capacitor, 10000 pF, 50 V, 0402 [1005 Metric], ± 10%, X7R, GRM Series"
			(at 0 0 270)
			(layer "F.Fab")
			(hide yes)
			(effects
				(font
					(size 1.27 1.27)
					(thickness 0.15)
				)
			)
		)
		(property "Author" "Antmicro"
			(at -24.45 189.85 0)
			(layer "F.Fab")
			(hide yes)
			(effects
				(font
					(size 1 1)
					(thickness 0.15)
				)
			)
		)
		(property "Dielectric" "X7R"
			(at -24.45 189.85 0)
			(layer "F.Fab")
			(hide yes)
			(effects
				(font
					(size 1 1)
					(thickness 0.15)
				)
			)
		)
		(property "License" "Apache-2.0"
			(at -24.45 189.85 0)
			(layer "F.Fab")
			(hide yes)
			(effects
				(font
					(size 1 1)
					(thickness 0.15)
				)
			)
		)
		(property "MPN" "GRM155R71H103KA88D"
			(at -24.45 189.85 0)
			(layer "F.Fab")
			(hide yes)
			(effects
				(font
					(size 1 1)
					(thickness 0.15)
				)
			)
		)
		(property "Manufacturer" "Murata"
			(at -24.45 189.85 0)
			(layer "F.Fab")
			(hide yes)
			(effects
				(font
					(size 1 1)
					(thickness 0.15)
				)
			)
		)
		(property "Val" "10n"
			(at -24.45 189.85 0)
			(layer "F.Fab")
			(hide yes)
			(effects
				(font
					(size 1 1)
					(thickness 0.15)
				)
			)
		)
		(property "Voltage" "50V"
			(at -24.45 189.85 0)
			(layer "F.Fab")
			(hide yes)
			(effects
				(font
					(size 1 1)
					(thickness 0.15)
				)
			)
		)
		(sheetname "/SDI/")
		(sheetfile "sdi.kicad_sch")
		(attr smd)
		(fp_rect
			(start -0.925 -0.47)
			(end 0.925 0.47)
			(stroke
				(width 0.05)
				(type default)
			)
			(fill no)
			(layer "F.CrtYd")
		)
		(fp_line
			(start -0.494 0.248)
			(end -0.494 -0.25)
			(stroke
				(width 0.15)
				(type solid)
			)
			(layer "F.Fab")
		)
		(fp_line
			(start 0.504 0.248)
			(end -0.494 0.248)
			(stroke
				(width 0.15)
				(type solid)
			)
			(layer "F.Fab")
		)
		(fp_line
			(start -0.494 -0.25)
			(end 0.504 -0.25)
			(stroke
				(width 0.15)
				(type solid)
			)
			(layer "F.Fab")
		)
		(fp_line
			(start 0.504 -0.25)
			(end 0.504 0.248)
			(stroke
				(width 0.15)
				(type solid)
			)
			(layer "F.Fab")
		)
		(fp_text user "License: Apache-2.0"
			(at -0.939 5.799 270)
			(layer "F.Fab")
			(effects
				(font
					(size 0.7 0.7)
					(thickness 0.15)
				)
				(justify left bottom)
			)
		)
		(fp_text user "${REFERENCE}"
			(at -0.939 4.599 270)
			(layer "F.Fab")
			(effects
				(font
					(size 0.7 0.7)
					(thickness 0.15)
				)
				(justify left bottom)
			)
		)
		(fp_text user "Author: Antmicro"
			(at -0.939 3.399 270)
			(layer "F.Fab")
			(effects
				(font
					(size 0.7 0.7)
					(thickness 0.15)
				)
				(justify left bottom)
			)
		)
		(pad "1" smd roundrect
			(at -0.48 0 270)
			(size 0.59 0.64)
			(layers "F.Cu" "F.Mask" "F.Paste")
			(roundrect_rratio 0.25)
			(net 2 "+3V3")
			(pintype "passive")
		)
		(pad "2" smd roundrect
			(at 0.48 0 270)
			(size 0.59 0.64)
			(layers "F.Cu" "F.Mask" "F.Paste")
			(roundrect_rratio 0.25)
			(net 1 "GND")
			(pintype "passive")
		)
	)
)
